# S9S_MB_2U (Grand Teton) — schematic netlist excerpt (pin names and nets, part order shuffled) for the footprints in the layout excerpt that follows; sources: Cadence DE-HDL packaged netlist, KiCad conversion of 03242023_DA0F0TMBIJ0_F0T_Motherboard_J_brd_V01_OCP.brd

R663  Q_RES  499 1% CHIP  pkg 0402LF  page 230 : A = PVNN_TERM_CPU1 ; B = I3C_SPD_DDRABCD_CPU1_SDA

(kicad_pcb
	(version 20260206)
	(generator "pcbnew")
	(generator_version "10.0")
	(general
		(thickness 1.6)
		(legacy_teardrops no)
	)
	(paper "A4")
	(title_block
		(title "03242023_DA0F0TMBIJ0_F0T_Motherboard_J_brd_V01_OCP.brd")
		(comment 1 "Grand Teton / footprints 4794-4795 of 6105")
	)
	(layers
		(0 "F.Cu" signal "TOP")
		(4 "In1.Cu" signal "GND")
		(6 "In2.Cu" signal "IN1")
		(8 "In3.Cu" signal "GND1")
		(10 "In4.Cu" signal "IN2")
		(12 "In5.Cu" signal "GND2")
		(14 "In6.Cu" signal "IN3")
		(16 "In7.Cu" signal "GND3")
		(18 "In8.Cu" signal "VCC")
		(20 "In9.Cu" signal "VCC1")
		(22 "In10.Cu" signal "GND4")
		(24 "In11.Cu" signal "IN4")
		(26 "In12.Cu" signal "GND5")
		(28 "In13.Cu" signal "IN5")
		(30 "In14.Cu" signal "GND6")
		(32 "In15.Cu" signal "IN6")
		(34 "In16.Cu" signal "GND7")
		(2 "B.Cu" signal "BOTTOM")
		(9 "F.Adhes" user "F.Adhesive")
		(11 "B.Adhes" user "B.Adhesive")
		(13 "F.Paste" user "Package Geometry/Pastemask Top")
		(15 "B.Paste" user "Package Geometry/Pastemask Bottom")
		(5 "F.SilkS" user "Ref Des/Silkscreen Top")
		(7 "B.SilkS" user "Ref Des/Silkscreen Bottom")
		(1 "F.Mask" user "Board Geometry/Soldermask Top")
		(3 "B.Mask" user "Board Geometry/Soldermask Bottom")
		(17 "Dwgs.User" user "User.Drawings")
		(19 "Cmts.User" user "User.Comments")
		(21 "Eco1.User" user "User.Eco1")
		(23 "Eco2.User" user "User.Eco2")
		(25 "Edge.Cuts" user "Board Geometry/Outline")
		(27 "Margin" user)
		(31 "F.CrtYd" user "Package Geometry/Place Bound Top")
		(29 "B.CrtYd" user "Package Geometry/Place Bound Bottom")
		(35 "F.Fab" user "Ref Des/Assembly Top")
		(33 "B.Fab" user "Ref Des/Assembly Bottom")
	)
	(footprint ""
		(layer "B.Cu")
		(at 94.209108 -190.705232 -90)
		(property "Reference" "R663"
			(at 0 0 90)
			(layer "B.SilkS")
			(hide yes)
			(effects
				(font
					(size 1.27 1.27)
				)
				(justify mirror)
			)
		)
		(property "Value" ""
			(at 0 0 90)
			(layer "B.Fab")
			(effects
				(font
					(size 1.27 1.27)
				)
				(justify mirror)
			)
		)
		(duplicate_pad_numbers_are_jumpers no)
		(fp_line
			(start -0.7874 0.4064)
			(end 0.7874 0.4064)
			(stroke
				(width 0.1524)
				(type default)
			)
			(layer "B.SilkS")
		)
		(fp_line
			(start 0.7874 0.4064)
			(end 0.7874 -0.4064)
			(stroke
				(width 0.1524)
				(type default)
			)
			(layer "B.SilkS")
		)
		(fp_line
			(start -0.7874 -0.4064)
			(end -0.7874 0.4064)
			(stroke
				(width 0.1524)
				(type default)
			)
			(layer "B.SilkS")
		)
		(fp_line
			(start 0.7874 -0.4064)
			(end -0.7874 -0.4064)
			(stroke
				(width 0.1524)
				(type default)
			)
			(layer "B.SilkS")
		)
		(fp_line
			(start -0.67945 0.3048)
			(end -0.120396 0.3048)
			(stroke
				(width 0.1)
				(type default)
			)
			(layer "B.Fab")
		)
		(fp_line
			(start -0.120396 0.3048)
			(end -0.120396 0.2794)
			(stroke
				(width 0.1)
				(type default)
			)
			(layer "B.Fab")
		)
		(fp_line
			(start 0.12065 0.3048)
			(end 0.67945 0.3048)
			(stroke
				(width 0.1)
				(type default)
			)
			(layer "B.Fab")
		)
		(fp_line
			(start 0.67945 0.3048)
			(end 0.67945 -0.305054)
			(stroke
				(width 0.1)
				(type default)
			)
			(layer "B.Fab")
		)
		(fp_line
			(start -0.120396 0.2794)
			(end 0.12065 0.2794)
			(stroke
				(width 0.1)
				(type default)
			)
			(layer "B.Fab")
		)
		(fp_line
			(start 0.12065 0.2794)
			(end 0.12065 0.3048)
			(stroke
				(width 0.1)
				(type default)
			)
			(layer "B.Fab")
		)
		(fp_line
			(start -0.12065 -0.2794)
			(end -0.12065 -0.3048)
			(stroke
				(width 0.1)
				(type default)
			)
			(layer "B.Fab")
		)
		(fp_line
			(start 0.12065 -0.2794)
			(end -0.12065 -0.2794)
			(stroke
				(width 0.1)
				(type default)
			)
			(layer "B.Fab")
		)
		(fp_line
			(start -0.67945 -0.3048)
			(end -0.67945 0.3048)
			(stroke
				(width 0.1)
				(type default)
			)
			(layer "B.Fab")
		)
		(fp_line
			(start -0.12065 -0.3048)
			(end -0.67945 -0.3048)
			(stroke
				(width 0.1)
				(type default)
			)
			(layer "B.Fab")
		)
		(fp_line
			(start 0.12065 -0.305054)
			(end 0.12065 -0.2794)
			(stroke
				(width 0.1)
				(type default)
			)
			(layer "B.Fab")
		)
		(fp_line
			(start 0.67945 -0.305054)
			(end 0.12065 -0.305054)
			(stroke
				(width 0.1)
				(type default)
			)
			(layer "B.Fab")
		)
		(pad "1" smd circle
			(at 0.40005 0 90)
			(size 0 0)
			(layers "B.Cu" "B.Mask" "B.Paste")
			(net "PVNN_TERM_CPU1")
		)
		(pad "2" smd circle
			(at -0.40005 0 90)
			(size 0 0)
			(layers "B.Cu" "B.Mask" "B.Paste")
			(net "I3C_SPD_DDRABCD_CPU1_SDA")
		)
	)
	(footprint ""
		(layer "B.Cu")
		(at 477.30537 -90.156792 90)
		(property "Reference" "X47"
			(at -2.272792 -2.22504 270)
			(unlocked yes)
			(layer "B.SilkS")
			(effects
				(font
					(size 0.7874 0.5842)
					(thickness 0.1524)
				)
				(justify left mirror)
			)
		)
		(property "Value" ""
			(at 0 0 90)
			(layer "B.Fab")
			(effects
				(font
					(size 1.27 1.27)
				)
				(justify mirror)
			)
		)
		(property "Device Type" "TP_TDR_4P_FTS_TH-TP_TDR_4P_DIPA"
			(at -1.30175 1.27 0)
			(unlocked yes)
			(layer "B.Fab")
			(hide yes)
			(effects
				(font
					(size 0.635 0.4064)
					(thickness 0.1524)
				)
				(justify mirror)
			)
		)
		(property "User Part Number" "N_A"
			(at -1.30175 1.27 0)
			(unlocked yes)
			(layer "Cmts.User")
			(hide yes)
			(effects
				(font
					(size 0.635 0.4064)
					(thickness 0.1524)
				)
				(justify mirror)
			)
		)
		(duplicate_pad_numbers_are_jumpers no)
		(fp_line
			(start 0 -1.27)
			(end 0 -0.635)
			(stroke
				(width 0.1524)
				(type default)
			)
			(layer "B.SilkS")
		)
		(fp_line
			(start -2.54 -1.27)
			(end 0 -1.27)
			(stroke
				(width 0.1524)
				(type default)
			)
			(layer "B.SilkS")
		)
		(fp_line
			(start -2.54 -1.1303)
			(end -2.54 -1.27)
			(stroke
				(width 0.1524)
				(type default)
			)
			(layer "B.SilkS")
		)
		(fp_line
			(start 0 0.635)
			(end 0 1.905)
			(stroke
				(width 0.1524)
				(type default)
			)
			(layer "B.SilkS")
		)
		(fp_line
			(start -2.54 1.4097)
			(end -2.54 1.1303)
			(stroke
				(width 0.1524)
				(type default)
			)
			(layer "B.SilkS")
		)
		(fp_line
			(start 0 3.175)
			(end 0 3.81)
			(stroke
				(width 0.1524)
				(type default)
			)
			(layer "B.SilkS")
		)
		(fp_line
			(start 0 3.81)
			(end -2.54 3.81)
			(stroke
				(width 0.1524)
				(type default)
			)
			(layer "B.SilkS")
		)
		(fp_line
			(start -2.54 3.81)
			(end -2.54 3.6703)
			(stroke
				(width 0.1524)
				(type default)
			)
			(layer "B.SilkS")
		)
		(fp_poly
			(pts
				(xy 0.761746 0) (xy 2.285746 -0.762) (xy 2.285746 0.762)
			)
			(stroke
				(width 0)
				(type default)
			)
			(fill yes)
			(layer "B.SilkS")
		)
		(fp_line
			(start 0 -1.27)
			(end 0 3.81)
			(stroke
				(width 0.1)
				(type default)
			)
			(layer "B.Fab")
		)
		(fp_line
			(start -2.54 -1.27)
			(end 0 -1.27)
			(stroke
				(width 0.1)
				(type default)
			)
			(layer "B.Fab")
		)
		(fp_line
			(start 0 3.81)
			(end -2.54 3.81)
			(stroke
				(width 0.1)
				(type default)
			)
			(layer "B.Fab")
		)
		(fp_line
			(start -2.54 3.81)
			(end -2.54 -1.27)
			(stroke
				(width 0.1)
				(type default)
			)
			(layer "B.Fab")
		)
		(fp_poly
			(pts
				(xy 0.761746 0) (xy 2.285746 -0.762) (xy 2.285746 0.762)
			)
			(stroke
				(width 0)
				(type default)
			)
			(fill yes)
			(layer "B.Fab")
		)
		(pad "1" thru_hole circle
			(at 0 0 270)
			(size 1.0033 1.0033)
			(drill 0.249936)
			(layers "*.Cu" "*.Mask")
			(remove_unused_layers no)
			(net "TDR_DIFF_85_NECK_IN6_DN")
			(clearance 0.10795)
			(padstack
				(mode front_inner_back)
				(layer "Inner"
					(shape circle)
					(size 0.8001 0.8001)
					(clearance 0.1524)
				)
				(layer "B.Cu"
					(shape circle)
					(size 1.0033 1.0033)
					(thermal_gap 0.10795)
					(clearance 0.10795)
				)
			)
		)
		(pad "2" thru_hole circle
			(at -2.54 0 270)
			(size 1.9939 1.9939)
			(drill 0.249936)
			(layers "*.Cu" "*.Mask")
			(remove_unused_layers no)
			(net "T1_GND")
			(clearance 0.10795)
			(padstack
				(mode front_inner_back)
				(layer "Inner"
					(shape circle)
					(size 0.8001 0.8001)
					(clearance 0.1524)
				)
				(layer "B.Cu"
					(shape circle)
					(size 1.9939 1.9939)
					(thermal_gap 0.10795)
					(clearance 0.10795)
				)
			)
		)
		(pad "3" thru_hole circle
			(at -2.54 2.54 270)
			(size 1.9939 1.9939)
			(drill 0.249936)
			(layers "*.Cu" "*.Mask")
			(remove_unused_layers no)
			(net "T1_GND")
			(clearance 0.10795)
			(padstack
				(mode front_inner_back)
				(layer "Inner"
					(shape circle)
					(size 0.8001 0.8001)
					(clearance 0.1524)
				)
				(layer "B.Cu"
					(shape circle)
					(size 1.9939 1.9939)
					(thermal_gap 0.10795)
					(clearance 0.10795)
				)
			)
		)
		(pad "4" thru_hole circle
			(at 0 2.54 270)
			(size 1.0033 1.0033)
			(drill 0.249936)
			(layers "*.Cu" "*.Mask")
			(remove_unused_layers no)
			(net "TDR_DIFF_85_NECK_IN6_DP")
			(clearance 0.10795)
			(padstack
				(mode front_inner_back)
				(layer "Inner"
					(shape circle)
					(size 0.8001 0.8001)
					(clearance 0.1524)
				)
				(layer "B.Cu"
					(shape circle)
					(size 1.0033 1.0033)
					(thermal_gap 0.10795)
					(clearance 0.10795)
				)
			)
		)
	)
)
